(kicad_pcb
	(version 20260206)
	(generator "pcbnew")
	(generator_version "10.0")
	(general
		(thickness 1.6)
		(legacy_teardrops no)
	)
	(paper "A4")
	(title_block
		(title "12092022_DA0F0TMDCD0_F0T_Management_Board_D_brd_V3_OCP.brd")
		(comment 1 "Grand Teton / footprints 622-627 of 1440")
	)
	(layers
		(0 "F.Cu" signal "TOP")
		(4 "In1.Cu" signal "GND")
		(6 "In2.Cu" signal "IN1")
		(8 "In3.Cu" signal "GND1")
		(10 "In4.Cu" signal "IN2")
		(12 "In5.Cu" signal "VCC")
		(14 "In6.Cu" signal "VCC1")
		(16 "In7.Cu" signal "IN3")
		(18 "In8.Cu" signal "GND2")
		(20 "In9.Cu" signal "IN4")
		(22 "In10.Cu" signal "GND3")
		(2 "B.Cu" signal "BOTTOM")
		(9 "F.Adhes" user "F.Adhesive")
		(11 "B.Adhes" user "B.Adhesive")
		(13 "F.Paste" user "Package Geometry/Pastemask Top")
		(15 "B.Paste" user "Package Geometry/Pastemask Bottom")
		(5 "F.SilkS" user "Ref Des/Silkscreen Top")
		(7 "B.SilkS" user "Ref Des/Silkscreen Bottom")
		(1 "F.Mask" user "Board Geometry/Soldermask Top")
		(3 "B.Mask" user "Board Geometry/Soldermask Bottom")
		(17 "Dwgs.User" user "User.Drawings")
		(19 "Cmts.User" user "User.Comments")
		(21 "Eco1.User" user "User.Eco1")
		(23 "Eco2.User" user "User.Eco2")
		(25 "Edge.Cuts" user "Board Geometry/Outline")
		(27 "Margin" user)
		(31 "F.CrtYd" user "Package Geometry/Place Bound Top")
		(29 "B.CrtYd" user "Package Geometry/Place Bound Bottom")
		(35 "F.Fab" user "Ref Des/Assembly Top")
		(33 "B.Fab" user "Ref Des/Assembly Bottom")
	)
	(footprint ""
		(layer "F.Cu")
		(at 25.527 -102.743 -90)
		(property "Reference" "R445"
			(at 0 0 270)
			(layer "F.SilkS")
			(hide yes)
			(effects
				(font
					(size 1.27 1.27)
				)
			)
		)
		(property "Value" ""
			(at 0 0 270)
			(layer "F.Fab")
			(effects
				(font
					(size 1.27 1.27)
				)
			)
		)
		(duplicate_pad_numbers_are_jumpers no)
		(fp_line
			(start -0.7874 0.4064)
			(end -0.7874 -0.4064)
			(stroke
				(width 0.1524)
				(type default)
			)
			(layer "F.SilkS")
		)
		(fp_line
			(start 0.7874 0.4064)
			(end -0.7874 0.4064)
			(stroke
				(width 0.1524)
				(type default)
			)
			(layer "F.SilkS")
		)
		(fp_line
			(start -0.7874 -0.4064)
			(end 0.7874 -0.4064)
			(stroke
				(width 0.1524)
				(type default)
			)
			(layer "F.SilkS")
		)
		(fp_line
			(start 0.7874 -0.4064)
			(end 0.7874 0.4064)
			(stroke
				(width 0.1524)
				(type default)
			)
			(layer "F.SilkS")
		)
		(fp_line
			(start -0.67945 0.3048)
			(end -0.67945 -0.305054)
			(stroke
				(width 0.1)
				(type default)
			)
			(layer "F.Fab")
		)
		(fp_line
			(start -0.12065 0.3048)
			(end -0.67945 0.3048)
			(stroke
				(width 0.1)
				(type default)
			)
			(layer "F.Fab")
		)
		(fp_line
			(start 0.120396 0.3048)
			(end 0.120396 0.2794)
			(stroke
				(width 0.1)
				(type default)
			)
			(layer "F.Fab")
		)
		(fp_line
			(start 0.67945 0.3048)
			(end 0.120396 0.3048)
			(stroke
				(width 0.1)
				(type default)
			)
			(layer "F.Fab")
		)
		(fp_line
			(start -0.12065 0.2794)
			(end -0.12065 0.3048)
			(stroke
				(width 0.1)
				(type default)
			)
			(layer "F.Fab")
		)
		(fp_line
			(start 0.120396 0.2794)
			(end -0.12065 0.2794)
			(stroke
				(width 0.1)
				(type default)
			)
			(layer "F.Fab")
		)
		(fp_line
			(start -0.12065 -0.2794)
			(end 0.12065 -0.2794)
			(stroke
				(width 0.1)
				(type default)
			)
			(layer "F.Fab")
		)
		(fp_line
			(start 0.12065 -0.2794)
			(end 0.12065 -0.3048)
			(stroke
				(width 0.1)
				(type default)
			)
			(layer "F.Fab")
		)
		(fp_line
			(start 0.12065 -0.3048)
			(end 0.67945 -0.3048)
			(stroke
				(width 0.1)
				(type default)
			)
			(layer "F.Fab")
		)
		(fp_line
			(start 0.67945 -0.3048)
			(end 0.67945 0.3048)
			(stroke
				(width 0.1)
				(type default)
			)
			(layer "F.Fab")
		)
		(fp_line
			(start -0.67945 -0.305054)
			(end -0.12065 -0.305054)
			(stroke
				(width 0.1)
				(type default)
			)
			(layer "F.Fab")
		)
		(fp_line
			(start -0.12065 -0.305054)
			(end -0.12065 -0.2794)
			(stroke
				(width 0.1)
				(type default)
			)
			(layer "F.Fab")
		)
		(pad "1" smd circle
			(at -0.40005 0 270)
			(size 0 0)
			(layers "F.Cu" "F.Mask" "F.Paste")
			(net "FM_BMC_SUSACK_N")
		)
		(pad "2" smd circle
			(at 0.40005 0 270)
			(size 0 0)
			(layers "F.Cu" "F.Mask" "F.Paste")
			(net "FM_BMC_SUSACK_R2_N")
		)
	)
	(footprint ""
		(layer "F.Cu")
		(at 58.266584 -34.637726 -90)
		(property "Reference" "R71"
			(at 0 0 270)
			(layer "F.SilkS")
			(hide yes)
			(effects
				(font
					(size 1.27 1.27)
				)
			)
		)
		(property "Value" ""
			(at 0 0 270)
			(layer "F.Fab")
			(effects
				(font
					(size 1.27 1.27)
				)
			)
		)
		(duplicate_pad_numbers_are_jumpers no)
		(fp_line
			(start -0.7874 0.4064)
			(end -0.7874 -0.4064)
			(stroke
				(width 0.1524)
				(type default)
			)
			(layer "F.SilkS")
		)
		(fp_line
			(start 0.7874 0.4064)
			(end -0.7874 0.4064)
			(stroke
				(width 0.1524)
				(type default)
			)
			(layer "F.SilkS")
		)
		(fp_line
			(start -0.7874 -0.4064)
			(end 0.7874 -0.4064)
			(stroke
				(width 0.1524)
				(type default)
			)
			(layer "F.SilkS")
		)
		(fp_line
			(start 0.7874 -0.4064)
			(end 0.7874 0.4064)
			(stroke
				(width 0.1524)
				(type default)
			)
			(layer "F.SilkS")
		)
		(fp_line
			(start -0.67945 0.3048)
			(end -0.67945 -0.305054)
			(stroke
				(width 0.1)
				(type default)
			)
			(layer "F.Fab")
		)
		(fp_line
			(start -0.12065 0.3048)
			(end -0.67945 0.3048)
			(stroke
				(width 0.1)
				(type default)
			)
			(layer "F.Fab")
		)
		(fp_line
			(start 0.120396 0.3048)
			(end 0.120396 0.2794)
			(stroke
				(width 0.1)
				(type default)
			)
			(layer "F.Fab")
		)
		(fp_line
			(start 0.67945 0.3048)
			(end 0.120396 0.3048)
			(stroke
				(width 0.1)
				(type default)
			)
			(layer "F.Fab")
		)
		(fp_line
			(start -0.12065 0.2794)
			(end -0.12065 0.3048)
			(stroke
				(width 0.1)
				(type default)
			)
			(layer "F.Fab")
		)
		(fp_line
			(start 0.120396 0.2794)
			(end -0.12065 0.2794)
			(stroke
				(width 0.1)
				(type default)
			)
			(layer "F.Fab")
		)
		(fp_line
			(start -0.12065 -0.2794)
			(end 0.12065 -0.2794)
			(stroke
				(width 0.1)
				(type default)
			)
			(layer "F.Fab")
		)
		(fp_line
			(start 0.12065 -0.2794)
			(end 0.12065 -0.3048)
			(stroke
				(width 0.1)
				(type default)
			)
			(layer "F.Fab")
		)
		(fp_line
			(start 0.12065 -0.3048)
			(end 0.67945 -0.3048)
			(stroke
				(width 0.1)
				(type default)
			)
			(layer "F.Fab")
		)
		(fp_line
			(start 0.67945 -0.3048)
			(end 0.67945 0.3048)
			(stroke
				(width 0.1)
				(type default)
			)
			(layer "F.Fab")
		)
		(fp_line
			(start -0.67945 -0.305054)
			(end -0.12065 -0.305054)
			(stroke
				(width 0.1)
				(type default)
			)
			(layer "F.Fab")
		)
		(fp_line
			(start -0.12065 -0.305054)
			(end -0.12065 -0.2794)
			(stroke
				(width 0.1)
				(type default)
			)
			(layer "F.Fab")
		)
		(pad "1" smd circle
			(at -0.40005 0 270)
			(size 0 0)
			(layers "F.Cu" "F.Mask" "F.Paste")
			(net "SMB_BMC_MM5_R_SCL")
		)
		(pad "2" smd circle
			(at 0.40005 0 270)
			(size 0 0)
			(layers "F.Cu" "F.Mask" "F.Paste")
			(net "SMB_BMC_MM5_SCL")
		)
	)
	(footprint ""
		(layer "F.Cu")
		(at 31.623 -66.7258 90)
		(property "Reference" "R757"
			(at 0 0 90)
			(layer "F.SilkS")
			(hide yes)
			(effects
				(font
					(size 1.27 1.27)
				)
			)
		)
		(property "Value" ""
			(at 0 0 90)
			(layer "F.Fab")
			(effects
				(font
					(size 1.27 1.27)
				)
			)
		)
		(duplicate_pad_numbers_are_jumpers no)
		(fp_line
			(start 0.7874 -0.4064)
			(end 0.7874 0.4064)
			(stroke
				(width 0.1524)
				(type default)
			)
			(layer "F.SilkS")
		)
		(fp_line
			(start -0.7874 -0.4064)
			(end 0.7874 -0.4064)
			(stroke
				(width 0.1524)
				(type default)
			)
			(layer "F.SilkS")
		)
		(fp_line
			(start 0.7874 0.4064)
			(end -0.7874 0.4064)
			(stroke
				(width 0.1524)
				(type default)
			)
			(layer "F.SilkS")
		)
		(fp_line
			(start -0.7874 0.4064)
			(end -0.7874 -0.4064)
			(stroke
				(width 0.1524)
				(type default)
			)
			(layer "F.SilkS")
		)
		(fp_line
			(start -0.12065 -0.305054)
			(end -0.12065 -0.2794)
			(stroke
				(width 0.1)
				(type default)
			)
			(layer "F.Fab")
		)
		(fp_line
			(start -0.67945 -0.305054)
			(end -0.12065 -0.305054)
			(stroke
				(width 0.1)
				(type default)
			)
			(layer "F.Fab")
		)
		(fp_line
			(start 0.67945 -0.3048)
			(end 0.67945 0.3048)
			(stroke
				(width 0.1)
				(type default)
			)
			(layer "F.Fab")
		)
		(fp_line
			(start 0.12065 -0.3048)
			(end 0.67945 -0.3048)
			(stroke
				(width 0.1)
				(type default)
			)
			(layer "F.Fab")
		)
		(fp_line
			(start 0.12065 -0.2794)
			(end 0.12065 -0.3048)
			(stroke
				(width 0.1)
				(type default)
			)
			(layer "F.Fab")
		)
		(fp_line
			(start -0.12065 -0.2794)
			(end 0.12065 -0.2794)
			(stroke
				(width 0.1)
				(type default)
			)
			(layer "F.Fab")
		)
		(fp_line
			(start 0.120396 0.2794)
			(end -0.12065 0.2794)
			(stroke
				(width 0.1)
				(type default)
			)
			(layer "F.Fab")
		)
		(fp_line
			(start -0.12065 0.2794)
			(end -0.12065 0.3048)
			(stroke
				(width 0.1)
				(type default)
			)
			(layer "F.Fab")
		)
		(fp_line
			(start 0.67945 0.3048)
			(end 0.120396 0.3048)
			(stroke
				(width 0.1)
				(type default)
			)
			(layer "F.Fab")
		)
		(fp_line
			(start 0.120396 0.3048)
			(end 0.120396 0.2794)
			(stroke
				(width 0.1)
				(type default)
			)
			(layer "F.Fab")
		)
		(fp_line
			(start -0.12065 0.3048)
			(end -0.67945 0.3048)
			(stroke
				(width 0.1)
				(type default)
			)
			(layer "F.Fab")
		)
		(fp_line
			(start -0.67945 0.3048)
			(end -0.67945 -0.305054)
			(stroke
				(width 0.1)
				(type default)
			)
			(layer "F.Fab")
		)
		(pad "1" smd circle
			(at -0.40005 0 90)
			(size 0 0)
			(layers "F.Cu" "F.Mask" "F.Paste")
			(net "UART_BMC_5_RXD_BUF1_R")
		)
		(pad "2" smd circle
			(at 0.40005 0 90)
			(size 0 0)
			(layers "F.Cu" "F.Mask" "F.Paste")
			(net "UART_BMC_5_RXD_R")
		)
	)
	(footprint ""
		(layer "F.Cu")
		(at 73.66 -16.256 -90)
		(property "Reference" "R391"
			(at 0 0 270)
			(layer "F.SilkS")
			(hide yes)
			(effects
				(font
					(size 1.27 1.27)
				)
			)
		)
		(property "Value" ""
			(at 0 0 270)
			(layer "F.Fab")
			(effects
				(font
					(size 1.27 1.27)
				)
			)
		)
		(duplicate_pad_numbers_are_jumpers no)
		(fp_line
			(start -0.7874 0.4064)
			(end -0.7874 -0.4064)
			(stroke
				(width 0.1524)
				(type default)
			)
			(layer "F.SilkS")
		)
		(fp_line
			(start 0.7874 0.4064)
			(end -0.7874 0.4064)
			(stroke
				(width 0.1524)
				(type default)
			)
			(layer "F.SilkS")
		)
		(fp_line
			(start -0.7874 -0.4064)
			(end 0.7874 -0.4064)
			(stroke
				(width 0.1524)
				(type default)
			)
			(layer "F.SilkS")
		)
		(fp_line
			(start 0.7874 -0.4064)
			(end 0.7874 0.4064)
			(stroke
				(width 0.1524)
				(type default)
			)
			(layer "F.SilkS")
		)
		(fp_line
			(start -0.67945 0.3048)
			(end -0.67945 -0.305054)
			(stroke
				(width 0.1)
				(type default)
			)
			(layer "F.Fab")
		)
		(fp_line
			(start -0.12065 0.3048)
			(end -0.67945 0.3048)
			(stroke
				(width 0.1)
				(type default)
			)
			(layer "F.Fab")
		)
		(fp_line
			(start 0.120396 0.3048)
			(end 0.120396 0.2794)
			(stroke
				(width 0.1)
				(type default)
			)
			(layer "F.Fab")
		)
		(fp_line
			(start 0.67945 0.3048)
			(end 0.120396 0.3048)
			(stroke
				(width 0.1)
				(type default)
			)
			(layer "F.Fab")
		)
		(fp_line
			(start -0.12065 0.2794)
			(end -0.12065 0.3048)
			(stroke
				(width 0.1)
				(type default)
			)
			(layer "F.Fab")
		)
		(fp_line
			(start 0.120396 0.2794)
			(end -0.12065 0.2794)
			(stroke
				(width 0.1)
				(type default)
			)
			(layer "F.Fab")
		)
		(fp_line
			(start -0.12065 -0.2794)
			(end 0.12065 -0.2794)
			(stroke
				(width 0.1)
				(type default)
			)
			(layer "F.Fab")
		)
		(fp_line
			(start 0.12065 -0.2794)
			(end 0.12065 -0.3048)
			(stroke
				(width 0.1)
				(type default)
			)
			(layer "F.Fab")
		)
		(fp_line
			(start 0.12065 -0.3048)
			(end 0.67945 -0.3048)
			(stroke
				(width 0.1)
				(type default)
			)
			(layer "F.Fab")
		)
		(fp_line
			(start 0.67945 -0.3048)
			(end 0.67945 0.3048)
			(stroke
				(width 0.1)
				(type default)
			)
			(layer "F.Fab")
		)
		(fp_line
			(start -0.67945 -0.305054)
			(end -0.12065 -0.305054)
			(stroke
				(width 0.1)
				(type default)
			)
			(layer "F.Fab")
		)
		(fp_line
			(start -0.12065 -0.305054)
			(end -0.12065 -0.2794)
			(stroke
				(width 0.1)
				(type default)
			)
			(layer "F.Fab")
		)
		(pad "1" smd circle
			(at -0.40005 0 270)
			(size 0 0)
			(layers "F.Cu" "F.Mask" "F.Paste")
			(net "P3V3_AUX")
		)
		(pad "2" smd circle
			(at 0.40005 0 270)
			(size 0 0)
			(layers "F.Cu" "F.Mask" "F.Paste")
			(net "REAR_AC_PWR_BTN_N")
		)
	)
	(footprint ""
		(layer "F.Cu")
		(at 77.947774 -72.413368)
		(property "Reference" "R764"
			(at 0 0 0)
			(layer "F.SilkS")
			(hide yes)
			(effects
				(font
					(size 1.27 1.27)
				)
			)
		)
		(property "Value" ""
			(at 0 0 0)
			(layer "F.Fab")
			(effects
				(font
					(size 1.27 1.27)
				)
			)
		)
		(duplicate_pad_numbers_are_jumpers no)
		(fp_line
			(start -0.7874 -0.4064)
			(end 0.7874 -0.4064)
			(stroke
				(width 0.1524)
				(type default)
			)
			(layer "F.SilkS")
		)
		(fp_line
			(start -0.7874 0.4064)
			(end -0.7874 -0.4064)
			(stroke
				(width 0.1524)
				(type default)
			)
			(layer "F.SilkS")
		)
		(fp_line
			(start 0.7874 -0.4064)
			(end 0.7874 0.4064)
			(stroke
				(width 0.1524)
				(type default)
			)
			(layer "F.SilkS")
		)
		(fp_line
			(start 0.7874 0.4064)
			(end -0.7874 0.4064)
			(stroke
				(width 0.1524)
				(type default)
			)
			(layer "F.SilkS")
		)
		(fp_line
			(start -0.67945 -0.305054)
			(end -0.12065 -0.305054)
			(stroke
				(width 0.1)
				(type default)
			)
			(layer "F.Fab")
		)
		(fp_line
			(start -0.67945 0.3048)
			(end -0.67945 -0.305054)
			(stroke
				(width 0.1)
				(type default)
			)
			(layer "F.Fab")
		)
		(fp_line
			(start -0.12065 -0.305054)
			(end -0.12065 -0.2794)
			(stroke
				(width 0.1)
				(type default)
			)
			(layer "F.Fab")
		)
		(fp_line
			(start -0.12065 -0.2794)
			(end 0.12065 -0.2794)
			(stroke
				(width 0.1)
				(type default)
			)
			(layer "F.Fab")
		)
		(fp_line
			(start -0.12065 0.2794)
			(end -0.12065 0.3048)
			(stroke
				(width 0.1)
				(type default)
			)
			(layer "F.Fab")
		)
		(fp_line
			(start -0.12065 0.3048)
			(end -0.67945 0.3048)
			(stroke
				(width 0.1)
				(type default)
			)
			(layer "F.Fab")
		)
		(fp_line
			(start 0.120396 0.2794)
			(end -0.12065 0.2794)
			(stroke
				(width 0.1)
				(type default)
			)
			(layer "F.Fab")
		)
		(fp_line
			(start 0.120396 0.3048)
			(end 0.120396 0.2794)
			(stroke
				(width 0.1)
				(type default)
			)
			(layer "F.Fab")
		)
		(fp_line
			(start 0.12065 -0.3048)
			(end 0.67945 -0.3048)
			(stroke
				(width 0.1)
				(type default)
			)
			(layer "F.Fab")
		)
		(fp_line
			(start 0.12065 -0.2794)
			(end 0.12065 -0.3048)
			(stroke
				(width 0.1)
				(type default)
			)
			(layer "F.Fab")
		)
		(fp_line
			(start 0.67945 -0.3048)
			(end 0.67945 0.3048)
			(stroke
				(width 0.1)
				(type default)
			)
			(layer "F.Fab")
		)
		(fp_line
			(start 0.67945 0.3048)
			(end 0.120396 0.3048)
			(stroke
				(width 0.1)
				(type default)
			)
			(layer "F.Fab")
		)
		(pad "1" smd circle
			(at -0.40005 0)
			(size 0 0)
			(layers "F.Cu" "F.Mask" "F.Paste")
			(net "PWRGD_P1V8_AUX")
		)
		(pad "2" smd circle
			(at 0.40005 0)
			(size 0 0)
			(layers "F.Cu" "F.Mask" "F.Paste")
			(net "EN_P1V2_AUX_R")
		)
	)
	(footprint ""
		(layer "F.Cu")
		(at 77.947774 -71.396352)
		(property "Reference" "R708"
			(at 0 0 0)
			(layer "F.SilkS")
			(hide yes)
			(effects
				(font
					(size 1.27 1.27)
				)
			)
		)
		(property "Value" ""
			(at 0 0 0)
			(layer "F.Fab")
			(effects
				(font
					(size 1.27 1.27)
				)
			)
		)
		(duplicate_pad_numbers_are_jumpers no)
		(fp_line
			(start -0.7874 -0.4064)
			(end 0.7874 -0.4064)
			(stroke
				(width 0.1524)
				(type default)
			)
			(layer "F.SilkS")
		)
		(fp_line
			(start -0.7874 0.4064)
			(end -0.7874 -0.4064)
			(stroke
				(width 0.1524)
				(type default)
			)
			(layer "F.SilkS")
		)
		(fp_line
			(start 0.7874 -0.4064)
			(end 0.7874 0.4064)
			(stroke
				(width 0.1524)
				(type default)
			)
			(layer "F.SilkS")
		)
		(fp_line
			(start 0.7874 0.4064)
			(end -0.7874 0.4064)
			(stroke
				(width 0.1524)
				(type default)
			)
			(layer "F.SilkS")
		)
		(fp_line
			(start -0.67945 -0.305054)
			(end -0.12065 -0.305054)
			(stroke
				(width 0.1)
				(type default)
			)
			(layer "F.Fab")
		)
		(fp_line
			(start -0.67945 0.3048)
			(end -0.67945 -0.305054)
			(stroke
				(width 0.1)
				(type default)
			)
			(layer "F.Fab")
		)
		(fp_line
			(start -0.12065 -0.305054)
			(end -0.12065 -0.2794)
			(stroke
				(width 0.1)
				(type default)
			)
			(layer "F.Fab")
		)
		(fp_line
			(start -0.12065 -0.2794)
			(end 0.12065 -0.2794)
			(stroke
				(width 0.1)
				(type default)
			)
			(layer "F.Fab")
		)
		(fp_line
			(start -0.12065 0.2794)
			(end -0.12065 0.3048)
			(stroke
				(width 0.1)
				(type default)
			)
			(layer "F.Fab")
		)
		(fp_line
			(start -0.12065 0.3048)
			(end -0.67945 0.3048)
			(stroke
				(width 0.1)
				(type default)
			)
			(layer "F.Fab")
		)
		(fp_line
			(start 0.120396 0.2794)
			(end -0.12065 0.2794)
			(stroke
				(width 0.1)
				(type default)
			)
			(layer "F.Fab")
		)
		(fp_line
			(start 0.120396 0.3048)
			(end 0.120396 0.2794)
			(stroke
				(width 0.1)
				(type default)
			)
			(layer "F.Fab")
		)
		(fp_line
			(start 0.12065 -0.3048)
			(end 0.67945 -0.3048)
			(stroke
				(width 0.1)
				(type default)
			)
			(layer "F.Fab")
		)
		(fp_line
			(start 0.12065 -0.2794)
			(end 0.12065 -0.3048)
			(stroke
				(width 0.1)
				(type default)
			)
			(layer "F.Fab")
		)
		(fp_line
			(start 0.67945 -0.3048)
			(end 0.67945 0.3048)
			(stroke
				(width 0.1)
				(type default)
			)
			(layer "F.Fab")
		)
		(fp_line
			(start 0.67945 0.3048)
			(end 0.120396 0.3048)
			(stroke
				(width 0.1)
				(type default)
			)
			(layer "F.Fab")
		)
		(pad "1" smd circle
			(at -0.40005 0)
			(size 0 0)
			(layers "F.Cu" "F.Mask" "F.Paste")
			(net "EN_P1V2_AUX")
		)
		(pad "2" smd circle
			(at 0.40005 0)
			(size 0 0)
			(layers "F.Cu" "F.Mask" "F.Paste")
			(net "EN_P1V2_AUX_R")
		)
	)
)
